(kicad_pcb
	(version 20260206)
	(generator "pcbnew")
	(generator_version "10.0")
	(general
		(thickness 1.6)
		(legacy_teardrops no)
	)
	(paper "A4")
	(title_block
		(title "v1-chassis-manager — T6M_CM_d_v01_1031_1645.brd")
		(comment 1 "Open CloudServer (Microsoft) / footprints 1306-1307 of 2512")
	)
	(layers
		(0 "F.Cu" signal "TOP")
		(4 "In1.Cu" signal "GND1")
		(6 "In2.Cu" signal "IN1")
		(8 "In3.Cu" signal "VCC1")
		(10 "In4.Cu" signal "VCC2")
		(12 "In5.Cu" signal "GND2")
		(14 "In6.Cu" signal "IN2")
		(16 "In7.Cu" signal "IN3")
		(18 "In8.Cu" signal "GND3")
		(2 "B.Cu" signal "BOTTOM")
		(9 "F.Adhes" user "F.Adhesive")
		(11 "B.Adhes" user "B.Adhesive")
		(13 "F.Paste" user "Package Geometry/Pastemask Top")
		(15 "B.Paste" user "Package Geometry/Pastemask Bottom")
		(5 "F.SilkS" user "Ref Des/Silkscreen Top")
		(7 "B.SilkS" user "Ref Des/Silkscreen Bottom")
		(1 "F.Mask" user "Board Geometry/Soldermask Top")
		(3 "B.Mask" user "Board Geometry/Soldermask Bottom")
		(17 "Dwgs.User" user "User.Drawings")
		(19 "Cmts.User" user "User.Comments")
		(21 "Eco1.User" user "User.Eco1")
		(23 "Eco2.User" user "User.Eco2")
		(25 "Edge.Cuts" user "Board Geometry/Outline")
		(27 "Margin" user)
		(31 "F.CrtYd" user "Package Geometry/Place Bound Top")
		(29 "B.CrtYd" user "Package Geometry/Place Bound Bottom")
		(35 "F.Fab" user "Ref Des/Assembly Top")
		(33 "B.Fab" user "Ref Des/Assembly Bottom")
	)
	(footprint ""
		(layer "F.Cu")
		(at 123.588018 -56.831484)
		(property "Reference" "R521"
			(at -3.77698 0.058928 0)
			(unlocked yes)
			(layer "F.SilkS")
			(effects
				(font
					(size 0.7874 0.5842)
					(thickness 0.1524)
				)
				(justify left)
			)
		)
		(property "Value" ""
			(at 0 0 0)
			(layer "F.Fab")
			(effects
				(font
					(size 1.27 1.27)
				)
			)
		)
		(duplicate_pad_numbers_are_jumpers no)
		(fp_line
			(start -0.7874 -0.4064)
			(end 0.7874 -0.4064)
			(stroke
				(width 0.1524)
				(type default)
			)
			(layer "F.SilkS")
		)
		(fp_line
			(start -0.7874 0.4064)
			(end -0.7874 -0.4064)
			(stroke
				(width 0.1524)
				(type default)
			)
			(layer "F.SilkS")
		)
		(fp_line
			(start 0.7874 -0.4064)
			(end 0.7874 0.4064)
			(stroke
				(width 0.1524)
				(type default)
			)
			(layer "F.SilkS")
		)
		(fp_line
			(start 0.7874 0.4064)
			(end -0.7874 0.4064)
			(stroke
				(width 0.1524)
				(type default)
			)
			(layer "F.SilkS")
		)
		(fp_poly
			(pts
				(xy -0.508 0.2794) (xy -0.508 0.2286) (xy -0.635 0.2286) (xy -0.635 -0.254) (xy -0.5334 -0.254)
				(xy -0.5334 -0.2794) (xy 0.5334 -0.2794) (xy 0.5334 -0.254) (xy 0.635 -0.254) (xy 0.635 0.254) (xy 0.5334 0.254)
				(xy 0.5334 0.2794)
			)
			(stroke
				(width 0)
				(type default)
			)
			(fill no)
			(layer "F.CrtYd")
		)
		(pad "1" smd rect
			(at 0.40005 0)
			(size 0.4572 0.508)
			(layers "F.Cu" "F.Mask" "F.Paste")
			(net "COM4_EN_N")
		)
		(pad "2" smd rect
			(at -0.40005 0)
			(size 0.4572 0.508)
			(layers "F.Cu" "F.Mask" "F.Paste")
			(net "CPLD_UART_RI_P3_N")
		)
	)
	(footprint ""
		(layer "F.Cu")
		(at -67.821048 -265.408664)
		(property "Reference" "PCB"
			(at -0.5842 -1.31953 0)
			(unlocked yes)
			(layer "B.SilkS")
			(effects
				(font
					(size 0.7874 0.5842)
					(thickness 0.1524)
				)
				(justify left mirror)
			)
		)
		(property "Value" ""
			(at 0 0 0)
			(layer "F.Fab")
			(effects
				(font
					(size 1.27 1.27)
				)
			)
		)
		(duplicate_pad_numbers_are_jumpers no)
		(fp_poly
			(pts
				(arc
					(start 0.3302 0)
					(mid -0.3302 0)
					(end 0.3302 0)
				)
			)
			(stroke
				(width 0)
				(type default)
			)
			(fill no)
			(layer "B.CrtYd")
		)
		(pad "1" thru_hole circle
			(at 0 0)
			(size 0.508 0.508)
			(drill 0.254)
			(layers "*.Cu" "*.Mask")
			(remove_unused_layers no)
			(net "Net_220")
			(clearance 0.127)
			(thermal_gap 0.127)
			(padstack
				(mode front_inner_back)
				(layer "Inner"
					(shape circle)
					(size 0.508 0.508)
					(clearance 0.127)
				)
				(layer "B.Cu"
					(shape circle)
					(size 0.6604 0.6604)
					(clearance 0.0508)
				)
			)
		)
	)
)
